# T6G (Grand Teton) — schematic netlist excerpt (pin names and nets, part order shuffled) for the footprints in the layout excerpt that follows; sources: Cadence DE-HDL packaged netlist, KiCad conversion of 04192023_DAF0TMB3IC0_F0TG_MB_C_brd_V02_OCP.brd

J69  SCONN288_DDR506112002KQ  IO  pkg DDR288S_1-1VXC  page 93
  VIN_BULK0  = P12V_MEM_CPU0
  RFU0  = NC
  VIN_MGMT  = P3V3_AUX
  HSCL  = I3C_SPD_DDRH_CPU0_SCL
  HSDA  = I3C_SPD_DDRH_CPU0_SDA
  VSS0  = GND
  DQ0_A  = M_H_CPU0_SA_DQ<0>
  VSS1  = GND
  DQ1_A  = M_H_CPU0_SA_DQ<1>
  VSS2  = GND
  DQS0_A_T  = M_H_CPU0_SA_DQS_DP<0>
  DQS0_A_C  = M_H_CPU0_SA_DQS_DN<0>
  VSS3  = GND
  DQ4_A  = M_H_CPU0_SA_DQ<4>
  VSS4  = GND
  DQ5_A  = M_H_CPU0_SA_DQ<5>
  VSS5  = GND
  DQ8_A  = M_H_CPU0_SA_DQ<8>
  VSS6  = GND
  DQ9_A  = M_H_CPU0_SA_DQ<9>
  VSS7  = GND
  DQS1_A_T  = M_H_CPU0_SA_DQS_DP<1>
  DQS1_A_C  = M_H_CPU0_SA_DQS_DN<1>
  VSS8  = GND
  DQ12_A  = M_H_CPU0_SA_DQ<12>
  VSS9  = GND
  DQ13_A  = M_H_CPU0_SA_DQ<13>
  VSS10  = GND
  DQ16_A  = M_H_CPU0_SA_DQ<16>
  VSS11  = GND
  DQ17_A  = M_H_CPU0_SA_DQ<17>
  VSS12  = GND
  DQS2_A_T  = M_H_CPU0_SA_DQS_DP<2>
  DQS2_A_C  = M_H_CPU0_SA_DQS_DN<2>
  VSS13  = GND
  DQ20_A  = M_H_CPU0_SA_DQ<20>
  VSS14  = GND
  DQ21_A  = M_H_CPU0_SA_DQ<21>
  VSS15  = GND
  DQ24_A  = M_H_CPU0_SA_DQ<24>
  VSS16  = GND
  DQ25_A  = M_H_CPU0_SA_DQ<25>
  VSS17  = GND
  DQS3_A_T  = M_H_CPU0_SA_DQS_DP<3>
  DQS3_A_C  = M_H_CPU0_SA_DQS_DN<3>
  VSS18  = GND
  DQ28_A  = M_H_CPU0_SA_DQ<28>
  VSS19  = GND
  DQ29_A  = M_H_CPU0_SA_DQ<29>
  VSS20  = GND
  CB0_A  = M_H_CPU0_SA_CB<0>
  VSS21  = GND
  CB1_A  = M_H_CPU0_SA_CB<1>
  VSS22  = GND
  DQS4_A_T  = M_H_CPU0_SA_DQS_DP<4>
  DQS4_A_C  = M_H_CPU0_SA_DQS_DN<4>
  VSS23  = GND
  CB4_A  = M_H_CPU0_SA_CB<4>
  VSS24  = GND
  CB5_A  = M_H_CPU0_SA_CB<5>
  VSS25  = GND
  ALERT_N  = M_H_CPU0_ALERT_N
  VSS26  = GND
  CS0_A_N  = M_H_CPU0_SA_CS_N<0>
  VSS27  = GND
  CA0_A  = M_H_CPU0_SA_CA<0>
  VSS28  = GND
  CA2_A  = M_H_CPU0_SA_CA<2>
  VSS29  = GND
  CA4_A  = M_H_CPU0_SA_CA<4>
  VSS30  = GND
  CA6_A  = M_H_CPU0_SA_CA<6>
  VSS31  = GND
  PAR_A  = M_H_CPU0_SA_PAR
  VSS32  = GND
  CA0_B  = M_H_CPU0_SB_CA<0>
  VSS33  = GND
  CA2_B  = M_H_CPU0_SB_CA<2>
  VSS34  = GND
  CA4_B  = M_H_CPU0_SB_CA<4>
  VSS35  = GND
  CA6_B  = M_H_CPU0_SB_CA<6>
  VSS36  = GND
  CS0_B_N  = M_H_CPU0_SB_CS_N<0>
  VSS37  = GND
  \lbd||rsp_a_n\  = M_H_CPU0_SA_RSP<0>
  \lbs||rsp_b_n\  = M_H_CPU0_SB_RSP<0>
  VSS38  = GND
  CB4_B  = M_H_CPU0_SB_CB<4>
  VSS39  = GND
  CB5_B  = M_H_CPU0_SB_CB<5>
  VSS40  = GND
  \dqs9_b_t||tdqs9_b_t||dbi4_b_n\  = M_H_CPU0_SB_DQS_DP<9>
  \dqs9_b_c||tdqs9_b_c\  = M_H_CPU0_SB_DQS_DN<9>
  VSS41  = GND
  CB0_B  = M_H_CPU0_SB_CB<0>
  VSS42  = GND
  CB1_B  = M_H_CPU0_SB_CB<1>
  VSS43  = GND
  DQ0_B  = M_H_CPU0_SB_DQ<0>
  VSS44  = GND
  DQ1_B  = M_H_CPU0_SB_DQ<1>
  VSS45  = GND
  DQS0_B_T  = M_H_CPU0_SB_DQS_DP<0>
  DQS0_B_C  = M_H_CPU0_SB_DQS_DN<0>
  VSS46  = GND
  DQ4_B  = M_H_CPU0_SB_DQ<4>
  VSS47  = GND
  DQ5_B  = M_H_CPU0_SB_DQ<5>
  VSS48  = GND
  DQ8_B  = M_H_CPU0_SB_DQ<8>
  VSS49  = GND
  DQ9_B  = M_H_CPU0_SB_DQ<9>
  VSS50  = GND
  DQS1_B_T  = M_H_CPU0_SB_DQS_DP<1>
  DQS1_B_C  = M_H_CPU0_SB_DQS_DN<1>
  VSS51  = GND
  DQ12_B  = M_H_CPU0_SB_DQ<12>
  VSS52  = GND
  DQ13_B  = M_H_CPU0_SB_DQ<13>
  VSS53  = GND
  DQ16_B  = M_H_CPU0_SB_DQ<16>
  VSS54  = GND
  DQ17_B  = M_H_CPU0_SB_DQ<17>
  VSS55  = GND
  DQS2_B_T  = M_H_CPU0_SB_DQS_DP<2>
  DQS2_B_C  = M_H_CPU0_SB_DQS_DN<2>
  VSS56  = GND
  DQ20_B  = M_H_CPU0_SB_DQ<20>
  VSS57  = GND
  DQ21_B  = M_H_CPU0_SB_DQ<21>
  VSS58  = GND
  DQ24_B  = M_H_CPU0_SB_DQ<24>
  VSS59  = GND
  DQ25_B  = M_H_CPU0_SB_DQ<25>
  VSS60  = GND
  DQS3_B_T  = M_H_CPU0_SB_DQS_DP<3>
  DQS3_B_C  = M_H_CPU0_SB_DQS_DN<3>
  VSS61  = GND
  DQ28_B  = M_H_CPU0_SB_DQ<28>
  VSS62  = GND
  DQ29_B  = M_H_CPU0_SB_DQ<29>
  VSS63  = GND
  RFU1  = NC
  VIN_BULK1  = P12V_MEM_CPU0
  VIN_BULK2  = P12V_MEM_CPU0
  \pwr_good||fail_n\  = PWRGD_CHH_CPU0_DIMM
  HAS  = PD_CHH_CPU0_DIMM_SAA
  RFU2  = NC
  RFU3  = NC
  VSS64  = GND
  DQ2_A  = M_H_CPU0_SA_DQ<2>
  VSS65  = GND
  DQ3_A  = M_H_CPU0_SA_DQ<3>
  VSS66  = GND
  \dqs5_a_c||tdqs5_a_c||dqs5_a_t||tdqs5_a_t\  = M_H_CPU0_SA_DQS_DN<5>
  \dqs5_a_t||tdqs5_a_t\  = M_H_CPU0_SA_DQS_DP<5>
  VSS67  = GND
  DQ6_A  = M_H_CPU0_SA_DQ<6>
  VSS68  = GND
  DQ7_A  = M_H_CPU0_SA_DQ<7>
  VSS69  = GND
  DQ10_A  = M_H_CPU0_SA_DQ<10>
  VSS70  = GND
  DQ11_A  = M_H_CPU0_SA_DQ<11>
  VSS71  = GND
  \dqs6_a_c||tdqs6_a_c||dqs6_a_t||tdqs6_a_t\  = M_H_CPU0_SA_DQS_DN<6>
  \dqs6_a_t||tdqs6_a_t\  = M_H_CPU0_SA_DQS_DP<6>
  VSS72  = GND
  DQ14_A  = M_H_CPU0_SA_DQ<14>
  VSS73  = GND
  DQ15_A  = M_H_CPU0_SA_DQ<15>
  VSS74  = GND
  DQ18_A  = M_H_CPU0_SA_DQ<18>
  VSS75  = GND
  DQ19_A  = M_H_CPU0_SA_DQ<19>
  VSS76  = GND
  \dqs7_a_c||tdqs7_a_c\  = M_H_CPU0_SA_DQS_DN<7>
  \dqs7_a_t||tdqs7_a_t\  = M_H_CPU0_SA_DQS_DP<7>
  VSS77  = GND
  DQ22_A  = M_H_CPU0_SA_DQ<22>
  VSS78  = GND
  DQ23_A  = M_H_CPU0_SA_DQ<23>
  VSS79  = GND
  DQ26_A  = M_H_CPU0_SA_DQ<26>
  VSS80  = GND
  DQ27_A  = M_H_CPU0_SA_DQ<27>
  VSS81  = GND
  \dqs8_a_c||tdqs8_a_c\  = M_H_CPU0_SA_DQS_DN<8>
  \dqs8_a_t||tdqs8_a_t\  = M_H_CPU0_SA_DQS_DP<8>
  VSS82  = GND
  DQ30_A  = M_H_CPU0_SA_DQ<30>
  VSS83  = GND
  DQ31_A  = M_H_CPU0_SA_DQ<31>
  VSS84  = GND
  CB2_A  = M_H_CPU0_SA_CB<2>
  VSS85  = GND
  CB3_A  = M_H_CPU0_SA_CB<3>
  VSS86  = GND
  \dqs9_a_c||tdqs9_a_c\  = M_H_CPU0_SA_DQS_DN<9>
  \dqs9_a_t||tdqs9_a_t\  = M_H_CPU0_SA_DQS_DP<9>
  VSS87  = GND
  CB6_A  = M_H_CPU0_SA_CB<6>
  VSS88  = GND
  CB7_A  = M_H_CPU0_SA_CB<7>
  VSS89  = GND
  RESET_N  = M_H_CPU0_RESET_N
  VSS90  = GND
  CS1_A_N  = M_H_CPU0_SA_CS_N<1>
  VSS91  = GND
  CA1_A  = M_H_CPU0_SA_CA<1>
  VSS92  = GND
  CA3_A  = M_H_CPU0_SA_CA<3>
  VSS93  = GND
  CA5_A  = M_H_CPU0_SA_CA<5>
  VSS94  = GND
  CK_T  = M_H_CPU0_CLK_DP<0>
  CK_C  = M_H_CPU0_CLK_DN<0>
  VSS95  = GND
  RFU4  = NC
  CA1_B  = M_H_CPU0_SB_CA<1>
  VSS96  = GND
  CA3_B  = M_H_CPU0_SB_CA<3>
  VSS97  = GND
  CA5_B  = M_H_CPU0_SB_CA<5>
  VSS98  = GND
  PAR_B  = M_H_CPU0_SB_PAR
  VSS99  = GND
  CS1_B_N  = M_H_CPU0_SB_CS_N<1>
  VSS100  = GND
  RFU5  = NC
  RFU6  = NC
  VSS101  = GND
  CB6_B  = M_H_CPU0_SB_CB<6>
  VSS102  = GND
  CB7_B  = M_H_CPU0_SB_CB<7>
  VSS103  = GND
  DQS4_B_C  = M_H_CPU0_SB_DQS_DN<4>
  DQS4_B_T  = M_H_CPU0_SB_DQS_DP<4>
  VSS104  = GND
  CB2_B  = M_H_CPU0_SB_CB<2>
  VSS105  = GND
  CB3_B  = M_H_CPU0_SB_CB<3>
  VSS106  = GND
  DQ2_B  = M_H_CPU0_SB_DQ<2>
  VSS107  = GND
  DQ3_B  = M_H_CPU0_SB_DQ<3>
  VSS108  = GND
  \dqs5_b_c||tdqs5_b_c\  = M_H_CPU0_SB_DQS_DN<5>
  \dqs5_b_t||tdqs5_b_t\  = M_H_CPU0_SB_DQS_DP<5>
  VSS109  = GND
  DQ6_B  = M_H_CPU0_SB_DQ<6>
  VSS110  = GND
  DQ7_B  = M_H_CPU0_SB_DQ<7>
  VSS111  = GND
  DQ10_B  = M_H_CPU0_SB_DQ<10>
  VSS112  = GND
  DQ11_B  = M_H_CPU0_SB_DQ<11>
  VSS113  = GND
  \dqs6_b_c||tdqs6_b_c\  = M_H_CPU0_SB_DQS_DN<6>
  \dqs6_b_t||tdqs6_b_t\  = M_H_CPU0_SB_DQS_DP<6>
  VSS114  = GND
  DQ14_B  = M_H_CPU0_SB_DQ<14>
  VSS115  = GND
  DQ15_B  = M_H_CPU0_SB_DQ<15>
  VSS116  = GND
  DQ18_B  = M_H_CPU0_SB_DQ<18>
  VSS117  = GND
  DQ19_B  = M_H_CPU0_SB_DQ<19>
  VSS118  = GND
  \dqs7_b_c||tdqs7_b_c\  = M_H_CPU0_SB_DQS_DN<7>
  \dqs7_b_t||tdqs7_b_t\  = M_H_CPU0_SB_DQS_DP<7>
  VSS119  = GND
  DQ22_B  = M_H_CPU0_SB_DQ<22>
  VSS120  = GND
  DQ23_B  = M_H_CPU0_SB_DQ<23>
  VSS121  = GND
  DQ26_B  = M_H_CPU0_SB_DQ<26>
  VSS122  = GND
  DQ27_B  = M_H_CPU0_SB_DQ<27>
  VSS123  = GND
  \dqs8_b_c||tdqs8_b_c\  = M_H_CPU0_SB_DQS_DN<8>
  \dqs8_b_t||tdqs8_b_t\  = M_H_CPU0_SB_DQS_DP<8>
  VSS124  = GND
  DQ30_B  = M_H_CPU0_SB_DQ<30>
  VSS125  = GND
  DQ31_B  = M_H_CPU0_SB_DQ<31>
  VSS126  = GND
  G1  = GND
  G2  = GND
  G3  = GND

(kicad_pcb
	(version 20260206)
	(generator "pcbnew")
	(generator_version "10.0")
	(general
		(thickness 1.6)
		(legacy_teardrops no)
	)
	(paper "A4")
	(title_block
		(title "04192023_DAF0TMB3IC0_F0TG_MB_C_brd_V02_OCP.brd")
		(comment 1 "Grand Teton / footprint 2335 of 8354 (J69), pads 1-46 of 291")
	)
	(layers
		(0 "F.Cu" signal "TOP")
		(4 "In1.Cu" signal "GND")
		(6 "In2.Cu" signal "IN1")
		(8 "In3.Cu" signal "GND1")
		(10 "In4.Cu" signal "IN2")
		(12 "In5.Cu" signal "GND2")
		(14 "In6.Cu" signal "IN3")
		(16 "In7.Cu" signal "GND3")
		(18 "In8.Cu" signal "VCC")
		(20 "In9.Cu" signal "VCC1")
		(22 "In10.Cu" signal "GND4")
		(24 "In11.Cu" signal "IN4")
		(26 "In12.Cu" signal "GND5")
		(28 "In13.Cu" signal "IN5")
		(30 "In14.Cu" signal "GND6")
		(32 "In15.Cu" signal "IN6")
		(34 "In16.Cu" signal "GND7")
		(2 "B.Cu" signal "BOTTOM")
		(9 "F.Adhes" user "F.Adhesive")
		(11 "B.Adhes" user "B.Adhesive")
		(13 "F.Paste" user "Package Geometry/Pastemask Top")
		(15 "B.Paste" user "Package Geometry/Pastemask Bottom")
		(5 "F.SilkS" user "Ref Des/Silkscreen Top")
		(7 "B.SilkS" user "Ref Des/Silkscreen Bottom")
		(1 "F.Mask" user "Board Geometry/Soldermask Top")
		(3 "B.Mask" user "Board Geometry/Soldermask Bottom")
		(17 "Dwgs.User" user "User.Drawings")
		(19 "Cmts.User" user "User.Comments")
		(21 "Eco1.User" user "User.Eco1")
		(23 "Eco2.User" user "User.Eco2")
		(25 "Edge.Cuts" user "Board Geometry/Outline")
		(27 "Margin" user)
		(31 "F.CrtYd" user "Package Geometry/Place Bound Top")
		(29 "B.CrtYd" user "Package Geometry/Place Bound Bottom")
		(35 "F.Fab" user "Ref Des/Assembly Top")
		(33 "B.Fab" user "Ref Des/Assembly Bottom")
	)
	(footprint ""
		(layer "F.Cu")
		(at 421.962072 -255.560068 180)
		(property "Reference" "J69"
			(at 3.448304 81.947512 0)
			(unlocked yes)
			(layer "F.SilkS")
			(effects
				(font
					(size 0.7874 0.5842)
					(thickness 0.1524)
				)
			)
		)
		(property "Value" ""
			(at 0 0 180)
			(layer "F.Fab")
			(effects
				(font
					(size 1.27 1.27)
				)
			)
		)
		(duplicate_pad_numbers_are_jumpers no)
		(pad "1" smd rect
			(at -2.050034 -63.324994 90)
			(size 0.519938 1.4986)
			(layers "F.Cu" "F.Mask" "F.Paste")
			(net "P12V_MEM_CPU0")
		)
		(pad "2" smd rect
			(at -2.050034 -62.47511 90)
			(size 0.519938 1.4986)
			(layers "F.Cu" "F.Mask" "F.Paste")
			(net "Net_2347")
		)
		(pad "3" smd rect
			(at -2.050034 -61.624972 90)
			(size 0.519938 1.4986)
			(layers "F.Cu" "F.Mask" "F.Paste")
			(net "P3V3_AUX")
		)
		(pad "4" smd rect
			(at -2.050034 -60.775088 90)
			(size 0.519938 1.4986)
			(layers "F.Cu" "F.Mask" "F.Paste")
			(net "I3C_SPD_DDRH_CPU0_SCL")
		)
		(pad "5" smd rect
			(at -2.050034 -59.92495 90)
			(size 0.519938 1.4986)
			(layers "F.Cu" "F.Mask" "F.Paste")
			(net "I3C_SPD_DDRH_CPU0_SDA")
		)
		(pad "6" smd rect
			(at -2.050034 -59.075066 90)
			(size 0.519938 1.4986)
			(layers "F.Cu" "F.Mask" "F.Paste")
			(net "GND")
		)
		(pad "7" smd rect
			(at -2.050034 -58.224928 90)
			(size 0.519938 1.4986)
			(layers "F.Cu" "F.Mask" "F.Paste")
			(net "M_H_CPU0_SA_DQ<0>")
		)
		(pad "8" smd rect
			(at -2.050034 -57.375044 90)
			(size 0.519938 1.4986)
			(layers "F.Cu" "F.Mask" "F.Paste")
			(net "GND")
		)
		(pad "9" smd rect
			(at -2.050034 -56.524906 90)
			(size 0.519938 1.4986)
			(layers "F.Cu" "F.Mask" "F.Paste")
			(net "M_H_CPU0_SA_DQ<1>")
		)
		(pad "10" smd rect
			(at -2.050034 -55.675022 90)
			(size 0.519938 1.4986)
			(layers "F.Cu" "F.Mask" "F.Paste")
			(net "GND")
		)
		(pad "11" smd rect
			(at -2.050034 -54.824884 90)
			(size 0.519938 1.4986)
			(layers "F.Cu" "F.Mask" "F.Paste")
			(net "M_H_CPU0_SA_DQS_DP<0>")
		)
		(pad "12" smd rect
			(at -2.050034 -53.975 90)
			(size 0.519938 1.4986)
			(layers "F.Cu" "F.Mask" "F.Paste")
			(net "M_H_CPU0_SA_DQS_DN<0>")
		)
		(pad "13" smd rect
			(at -2.050034 -53.125116 90)
			(size 0.519938 1.4986)
			(layers "F.Cu" "F.Mask" "F.Paste")
			(net "GND")
		)
		(pad "14" smd rect
			(at -2.050034 -52.274978 90)
			(size 0.519938 1.4986)
			(layers "F.Cu" "F.Mask" "F.Paste")
			(net "M_H_CPU0_SA_DQ<4>")
		)
		(pad "15" smd rect
			(at -2.050034 -51.425094 90)
			(size 0.519938 1.4986)
			(layers "F.Cu" "F.Mask" "F.Paste")
			(net "GND")
		)
		(pad "16" smd rect
			(at -2.050034 -50.574956 90)
			(size 0.519938 1.4986)
			(layers "F.Cu" "F.Mask" "F.Paste")
			(net "M_H_CPU0_SA_DQ<5>")
		)
		(pad "17" smd rect
			(at -2.050034 -49.725072 90)
			(size 0.519938 1.4986)
			(layers "F.Cu" "F.Mask" "F.Paste")
			(net "GND")
		)
		(pad "18" smd rect
			(at -2.050034 -48.874934 90)
			(size 0.519938 1.4986)
			(layers "F.Cu" "F.Mask" "F.Paste")
			(net "M_H_CPU0_SA_DQ<8>")
		)
		(pad "19" smd rect
			(at -2.050034 -48.02505 90)
			(size 0.519938 1.4986)
			(layers "F.Cu" "F.Mask" "F.Paste")
			(net "GND")
		)
		(pad "20" smd rect
			(at -2.050034 -47.174912 90)
			(size 0.519938 1.4986)
			(layers "F.Cu" "F.Mask" "F.Paste")
			(net "M_H_CPU0_SA_DQ<9>")
		)
		(pad "21" smd rect
			(at -2.050034 -46.325028 90)
			(size 0.519938 1.4986)
			(layers "F.Cu" "F.Mask" "F.Paste")
			(net "GND")
		)
		(pad "22" smd rect
			(at -2.050034 -45.47489 90)
			(size 0.519938 1.4986)
			(layers "F.Cu" "F.Mask" "F.Paste")
			(net "M_H_CPU0_SA_DQS_DP<1>")
		)
		(pad "23" smd rect
			(at -2.050034 -44.625006 90)
			(size 0.519938 1.4986)
			(layers "F.Cu" "F.Mask" "F.Paste")
			(net "M_H_CPU0_SA_DQS_DN<1>")
		)
		(pad "24" smd rect
			(at -2.050034 -43.775122 90)
			(size 0.519938 1.4986)
			(layers "F.Cu" "F.Mask" "F.Paste")
			(net "GND")
		)
		(pad "25" smd rect
			(at -2.050034 -42.924984 90)
			(size 0.519938 1.4986)
			(layers "F.Cu" "F.Mask" "F.Paste")
			(net "M_H_CPU0_SA_DQ<12>")
		)
		(pad "26" smd rect
			(at -2.050034 -42.0751 90)
			(size 0.519938 1.4986)
			(layers "F.Cu" "F.Mask" "F.Paste")
			(net "GND")
		)
		(pad "27" smd rect
			(at -2.050034 -41.224962 90)
			(size 0.519938 1.4986)
			(layers "F.Cu" "F.Mask" "F.Paste")
			(net "M_H_CPU0_SA_DQ<13>")
		)
		(pad "28" smd rect
			(at -2.050034 -40.375078 90)
			(size 0.519938 1.4986)
			(layers "F.Cu" "F.Mask" "F.Paste")
			(net "GND")
		)
		(pad "29" smd rect
			(at -2.050034 -39.52494 90)
			(size 0.519938 1.4986)
			(layers "F.Cu" "F.Mask" "F.Paste")
			(net "M_H_CPU0_SA_DQ<16>")
		)
		(pad "30" smd rect
			(at -2.050034 -38.675056 90)
			(size 0.519938 1.4986)
			(layers "F.Cu" "F.Mask" "F.Paste")
			(net "GND")
		)
		(pad "31" smd rect
			(at -2.050034 -37.824918 90)
			(size 0.519938 1.4986)
			(layers "F.Cu" "F.Mask" "F.Paste")
			(net "M_H_CPU0_SA_DQ<17>")
		)
		(pad "32" smd rect
			(at -2.050034 -36.975034 90)
			(size 0.519938 1.4986)
			(layers "F.Cu" "F.Mask" "F.Paste")
			(net "GND")
		)
		(pad "33" smd rect
			(at -2.050034 -36.124896 90)
			(size 0.519938 1.4986)
			(layers "F.Cu" "F.Mask" "F.Paste")
			(net "M_H_CPU0_SA_DQS_DP<2>")
		)
		(pad "34" smd rect
			(at -2.050034 -35.275012 90)
			(size 0.519938 1.4986)
			(layers "F.Cu" "F.Mask" "F.Paste")
			(net "M_H_CPU0_SA_DQS_DN<2>")
		)
		(pad "35" smd rect
			(at -2.050034 -34.425128 90)
			(size 0.519938 1.4986)
			(layers "F.Cu" "F.Mask" "F.Paste")
			(net "GND")
		)
		(pad "36" smd rect
			(at -2.050034 -33.57499 90)
			(size 0.519938 1.4986)
			(layers "F.Cu" "F.Mask" "F.Paste")
			(net "M_H_CPU0_SA_DQ<20>")
		)
		(pad "37" smd rect
			(at -2.050034 -32.725106 90)
			(size 0.519938 1.4986)
			(layers "F.Cu" "F.Mask" "F.Paste")
			(net "GND")
		)
		(pad "38" smd rect
			(at -2.050034 -31.874968 90)
			(size 0.519938 1.4986)
			(layers "F.Cu" "F.Mask" "F.Paste")
			(net "M_H_CPU0_SA_DQ<21>")
		)
		(pad "39" smd rect
			(at -2.050034 -31.025084 90)
			(size 0.519938 1.4986)
			(layers "F.Cu" "F.Mask" "F.Paste")
			(net "GND")
		)
		(pad "40" smd rect
			(at -2.050034 -30.174946 90)
			(size 0.519938 1.4986)
			(layers "F.Cu" "F.Mask" "F.Paste")
			(net "M_H_CPU0_SA_DQ<24>")
		)
		(pad "41" smd rect
			(at -2.050034 -29.325062 90)
			(size 0.519938 1.4986)
			(layers "F.Cu" "F.Mask" "F.Paste")
			(net "GND")
		)
		(pad "42" smd rect
			(at -2.050034 -28.474924 90)
			(size 0.519938 1.4986)
			(layers "F.Cu" "F.Mask" "F.Paste")
			(net "M_H_CPU0_SA_DQ<25>")
		)
		(pad "43" smd rect
			(at -2.050034 -27.62504 90)
			(size 0.519938 1.4986)
			(layers "F.Cu" "F.Mask" "F.Paste")
			(net "GND")
		)
		(pad "44" smd rect
			(at -2.050034 -26.774902 90)
			(size 0.519938 1.4986)
			(layers "F.Cu" "F.Mask" "F.Paste")
			(net "M_H_CPU0_SA_DQS_DP<3>")
		)
		(pad "45" smd rect
			(at -2.050034 -25.925018 90)
			(size 0.519938 1.4986)
			(layers "F.Cu" "F.Mask" "F.Paste")
			(net "M_H_CPU0_SA_DQS_DN<3>")
		)
		(pad "46" smd rect
			(at -2.050034 -25.07488 90)
			(size 0.519938 1.4986)
			(layers "F.Cu" "F.Mask" "F.Paste")
			(net "GND")
		)
	)
)
